(kicad_pcb
	(version 20260206)
	(generator "pcbnew")
	(generator_version "10.0")
	(general
		(thickness 1.6)
		(legacy_teardrops no)
	)
	(paper "A4")
	(title_block
		(title "Bryce Canyon_R.DPB_16317-1_OCP.brd")
		(comment 1 "Bryce Canyon / footprints 1548-1554 of 2099")
	)
	(layers
		(0 "F.Cu" signal "TOP")
		(4 "In1.Cu" signal "L2GND")
		(6 "In2.Cu" signal "L3")
		(8 "In3.Cu" signal "L4VCC")
		(10 "In4.Cu" signal "L5VCC")
		(12 "In5.Cu" signal "L6")
		(14 "In6.Cu" signal "L7GND")
		(2 "B.Cu" signal "BOTTOM")
		(9 "F.Adhes" user "F.Adhesive")
		(11 "B.Adhes" user "B.Adhesive")
		(13 "F.Paste" user "Package Geometry/Pastemask Top")
		(15 "B.Paste" user "Package Geometry/Pastemask Bottom")
		(5 "F.SilkS" user "Ref Des/Silkscreen Top")
		(7 "B.SilkS" user "Ref Des/Silkscreen Bottom")
		(1 "F.Mask" user "Board Geometry/Soldermask Top")
		(3 "B.Mask" user "Board Geometry/Soldermask Bottom")
		(17 "Dwgs.User" user "User.Drawings")
		(19 "Cmts.User" user "User.Comments")
		(21 "Eco1.User" user "User.Eco1")
		(23 "Eco2.User" user "User.Eco2")
		(25 "Edge.Cuts" user "Board Geometry/Outline")
		(27 "Margin" user)
		(31 "F.CrtYd" user "Package Geometry/Place Bound Top")
		(29 "B.CrtYd" user "Package Geometry/Place Bound Bottom")
		(35 "F.Fab" user "Ref Des/Assembly Top")
		(33 "B.Fab" user "Ref Des/Assembly Bottom")
	)
	(footprint ""
		(layer "F.Cu")
		(at 424.434 -45.339 180)
		(property "Reference" "C466"
			(at 0 0 180)
			(layer "F.SilkS")
			(hide yes)
			(effects
				(font
					(size 1.27 1.27)
				)
			)
		)
		(property "Value" "SC1U25V3KX-GP"
			(at 0 -2.8194 180)
			(unlocked yes)
			(layer "F.Fab")
			(hide yes)
			(effects
				(font
					(size 1.016 1.016)
					(thickness 0.1524)
				)
			)
		)
		(property "Device Type" "C603H36"
			(at 0 -4.3434 180)
			(unlocked yes)
			(layer "F.Fab")
			(hide yes)
			(effects
				(font
					(size 1.016 1.016)
					(thickness 0.1524)
				)
			)
		)
		(duplicate_pad_numbers_are_jumpers no)
		(fp_line
			(start 0.508 0)
			(end -0.508 0)
			(stroke
				(width 0.2032)
				(type default)
			)
			(layer "F.SilkS")
		)
		(fp_rect
			(start -0.5842 1.3335)
			(end 0.5842 -1.3335)
			(stroke
				(width 0)
				(type default)
			)
			(fill no)
			(layer "F.CrtYd")
		)
		(fp_rect
			(start -0.5842 1.3335)
			(end 0.5842 -1.3335)
			(stroke
				(width 0)
				(type default)
			)
			(fill no)
			(layer "F.Fab")
		)
		(pad "1" smd custom
			(at 0 -0.762 180)
			(size 0.2159 0.2159)
			(layers "F.Cu" "F.Mask" "F.Paste")
			(net "P12V_HDD33")
			(options
				(clearance outline)
				(anchor circle)
			)
			(primitives
				(gr_poly
					(pts
						(arc
							(start -0.3302 -0.4318)
							(mid -0.402042 -0.402042)
							(end -0.4318 -0.3302)
						)
						(arc
							(start -0.4318 0.3302)
							(mid -0.402042 0.402042)
							(end -0.3302 0.4318)
						)
						(arc
							(start 0.3302 0.4318)
							(mid 0.402042 0.402042)
							(end 0.4318 0.3302)
						)
						(arc
							(start 0.4318 -0.3302)
							(mid 0.402042 -0.402042)
							(end 0.3302 -0.4318)
						)
					)
					(width 0)
					(fill yes)
				)
			)
		)
		(pad "2" smd custom
			(at 0 0.762 180)
			(size 0.2159 0.2159)
			(layers "F.Cu" "F.Mask" "F.Paste")
			(net "GND")
			(options
				(clearance outline)
				(anchor circle)
			)
			(primitives
				(gr_poly
					(pts
						(arc
							(start -0.3302 -0.4318)
							(mid -0.402042 -0.402042)
							(end -0.4318 -0.3302)
						)
						(arc
							(start -0.4318 0.3302)
							(mid -0.402042 0.402042)
							(end -0.3302 0.4318)
						)
						(arc
							(start 0.3302 0.4318)
							(mid 0.402042 0.402042)
							(end 0.4318 0.3302)
						)
						(arc
							(start 0.4318 -0.3302)
							(mid 0.402042 -0.402042)
							(end 0.3302 -0.4318)
						)
					)
					(width 0)
					(fill yes)
				)
			)
		)
	)
	(footprint ""
		(layer "F.Cu")
		(at 336.931 -131.826 180)
		(property "Reference" "R498"
			(at 0 0 180)
			(layer "F.SilkS")
			(hide yes)
			(effects
				(font
					(size 1.27 1.27)
				)
			)
		)
		(property "Value" "4K7R2J-2-GP"
			(at 0.064008 -3.993896 180)
			(unlocked yes)
			(layer "F.Fab")
			(hide yes)
			(effects
				(font
					(size 1.016 1.016)
					(thickness 0.1524)
				)
			)
		)
		(property "Device Type" "R402H16"
			(at 0.064008 -5.517896 180)
			(unlocked yes)
			(layer "F.Fab")
			(hide yes)
			(effects
				(font
					(size 1.016 1.016)
					(thickness 0.1524)
				)
			)
		)
		(duplicate_pad_numbers_are_jumpers no)
		(fp_line
			(start 0.508 -0.9398)
			(end -0.508 -0.9398)
			(stroke
				(width 0.1524)
				(type default)
			)
			(layer "F.SilkS")
		)
		(fp_line
			(start -0.508 -0.9398)
			(end -0.508 0.9398)
			(stroke
				(width 0.1524)
				(type default)
			)
			(layer "F.SilkS")
		)
		(fp_rect
			(start -0.508 0.9398)
			(end 0.508 -0.9398)
			(stroke
				(width 0)
				(type default)
			)
			(fill no)
			(layer "F.CrtYd")
		)
		(fp_rect
			(start -0.508 0.9398)
			(end 0.508 -0.9398)
			(stroke
				(width 0)
				(type default)
			)
			(fill no)
			(layer "F.Fab")
		)
		(pad "1" smd custom
			(at 0 -0.4445 180)
			(size 0.1397 0.1397)
			(layers "F.Cu" "F.Mask" "F.Paste")
			(net "P12V_B")
			(options
				(clearance outline)
				(anchor circle)
			)
			(primitives
				(gr_poly
					(pts
						(arc
							(start -0.1778 -0.2794)
							(mid -0.249642 -0.249642)
							(end -0.2794 -0.1778)
						)
						(arc
							(start -0.2794 0.1778)
							(mid -0.249642 0.249642)
							(end -0.1778 0.2794)
						)
						(arc
							(start 0.1778 0.2794)
							(mid 0.249642 0.249642)
							(end 0.2794 0.1778)
						)
						(arc
							(start 0.2794 -0.1778)
							(mid 0.249642 -0.249642)
							(end 0.1778 -0.2794)
						)
					)
					(width 0)
					(fill yes)
				)
			)
		)
		(pad "2" smd custom
			(at 0 0.4445 180)
			(size 0.1397 0.1397)
			(layers "F.Cu" "F.Mask" "F.Paste")
			(net "SW_HDD_R18")
			(options
				(clearance outline)
				(anchor circle)
			)
			(primitives
				(gr_poly
					(pts
						(arc
							(start -0.1778 -0.2794)
							(mid -0.249642 -0.249642)
							(end -0.2794 -0.1778)
						)
						(arc
							(start -0.2794 0.1778)
							(mid -0.249642 0.249642)
							(end -0.1778 0.2794)
						)
						(arc
							(start 0.1778 0.2794)
							(mid 0.249642 0.249642)
							(end 0.2794 0.1778)
						)
						(arc
							(start 0.2794 -0.1778)
							(mid 0.249642 -0.249642)
							(end 0.1778 -0.2794)
						)
					)
					(width 0)
					(fill yes)
				)
			)
		)
	)
	(footprint ""
		(layer "F.Cu")
		(at 398.907 -131.826 180)
		(property "Reference" "R547"
			(at 0 0 180)
			(layer "F.SilkS")
			(hide yes)
			(effects
				(font
					(size 1.27 1.27)
				)
			)
		)
		(property "Value" "0R2J-2-GP"
			(at 0.064008 -3.993896 180)
			(unlocked yes)
			(layer "F.Fab")
			(hide yes)
			(effects
				(font
					(size 1.016 1.016)
					(thickness 0.1524)
				)
			)
		)
		(property "Device Type" "R402H16"
			(at 0.064008 -5.517896 180)
			(unlocked yes)
			(layer "F.Fab")
			(hide yes)
			(effects
				(font
					(size 1.016 1.016)
					(thickness 0.1524)
				)
			)
		)
		(duplicate_pad_numbers_are_jumpers no)
		(fp_line
			(start 0.508 -0.9398)
			(end -0.508 -0.9398)
			(stroke
				(width 0.1524)
				(type default)
			)
			(layer "F.SilkS")
		)
		(fp_line
			(start -0.508 -0.9398)
			(end -0.508 0.9398)
			(stroke
				(width 0.1524)
				(type default)
			)
			(layer "F.SilkS")
		)
		(fp_rect
			(start -0.508 0.9398)
			(end 0.508 -0.9398)
			(stroke
				(width 0)
				(type default)
			)
			(fill no)
			(layer "F.CrtYd")
		)
		(fp_rect
			(start -0.508 0.9398)
			(end 0.508 -0.9398)
			(stroke
				(width 0)
				(type default)
			)
			(fill no)
			(layer "F.Fab")
		)
		(pad "1" smd custom
			(at 0 -0.4445 180)
			(size 0.1397 0.1397)
			(layers "F.Cu" "F.Mask" "F.Paste")
			(net "SW_HDD_G20")
			(options
				(clearance outline)
				(anchor circle)
			)
			(primitives
				(gr_poly
					(pts
						(arc
							(start -0.1778 -0.2794)
							(mid -0.249642 -0.249642)
							(end -0.2794 -0.1778)
						)
						(arc
							(start -0.2794 0.1778)
							(mid -0.249642 0.249642)
							(end -0.1778 0.2794)
						)
						(arc
							(start 0.1778 0.2794)
							(mid 0.249642 0.249642)
							(end 0.2794 0.1778)
						)
						(arc
							(start 0.2794 -0.1778)
							(mid 0.249642 -0.249642)
							(end 0.1778 -0.2794)
						)
					)
					(width 0)
					(fill yes)
				)
			)
		)
		(pad "2" smd custom
			(at 0 0.4445 180)
			(size 0.1397 0.1397)
			(layers "F.Cu" "F.Mask" "F.Paste")
			(net "SW_HDD_R20")
			(options
				(clearance outline)
				(anchor circle)
			)
			(primitives
				(gr_poly
					(pts
						(arc
							(start -0.1778 -0.2794)
							(mid -0.249642 -0.249642)
							(end -0.2794 -0.1778)
						)
						(arc
							(start -0.2794 0.1778)
							(mid -0.249642 0.249642)
							(end -0.1778 0.2794)
						)
						(arc
							(start 0.1778 0.2794)
							(mid 0.249642 0.249642)
							(end 0.2794 0.1778)
						)
						(arc
							(start 0.2794 -0.1778)
							(mid 0.249642 -0.249642)
							(end 0.1778 -0.2794)
						)
					)
					(width 0)
					(fill yes)
				)
			)
		)
	)
	(footprint ""
		(layer "F.Cu")
		(at 429.514 -138.938 -90)
		(property "Reference" "Q100"
			(at 0 0 270)
			(layer "F.SilkS")
			(hide yes)
			(effects
				(font
					(size 1.27 1.27)
				)
			)
		)
		(property "Value" "AO4406AL-GP"
			(at -3.707384 -1.5367 270)
			(unlocked yes)
			(layer "F.Fab")
			(hide yes)
			(effects
				(font
					(size 1.016 1.016)
					(thickness 0.1524)
				)
			)
		)
		(property "Device Type" "SOIC8H69"
			(at -3.707384 -3.0607 270)
			(unlocked yes)
			(layer "F.Fab")
			(hide yes)
			(effects
				(font
					(size 1.016 1.016)
					(thickness 0.1524)
				)
			)
		)
		(duplicate_pad_numbers_are_jumpers no)
		(fp_line
			(start -2.6289 3.4417)
			(end -2.6289 1.4732)
			(stroke
				(width 0.381)
				(type default)
			)
			(layer "F.SilkS")
		)
		(fp_line
			(start -2.7432 1.4224)
			(end -2.6416 1.4224)
			(stroke
				(width 0.1524)
				(type default)
			)
			(layer "F.SilkS")
		)
		(fp_line
			(start -2.7432 1.4224)
			(end 2.1336 1.4224)
			(stroke
				(width 0.1524)
				(type default)
			)
			(layer "F.SilkS")
		)
		(fp_line
			(start 2.1336 1.4224)
			(end 2.1336 -1.4224)
			(stroke
				(width 0.1524)
				(type default)
			)
			(layer "F.SilkS")
		)
		(fp_line
			(start -2.1844 -0.0508)
			(end -2.7178 0.508)
			(stroke
				(width 0.1524)
				(type default)
			)
			(layer "F.SilkS")
		)
		(fp_line
			(start -2.7178 -0.508)
			(end -2.1844 -0.0508)
			(stroke
				(width 0.1524)
				(type default)
			)
			(layer "F.SilkS")
		)
		(fp_line
			(start -2.7432 -1.4224)
			(end -2.7432 1.4224)
			(stroke
				(width 0.1524)
				(type default)
			)
			(layer "F.SilkS")
		)
		(fp_line
			(start 2.1336 -1.4224)
			(end -2.7432 -1.4224)
			(stroke
				(width 0.1524)
				(type default)
			)
			(layer "F.SilkS")
		)
		(fp_poly
			(pts
				(xy -2.2098 -1.4224) (xy -2.2098 1.4224) (xy 2.2098 1.4224) (xy 2.2098 -1.4224)
			)
			(stroke
				(width 0)
				(type default)
			)
			(fill yes)
			(layer "F.SilkS")
		)
		(fp_rect
			(start -2.450084 2.999994)
			(end 2.450084 -2.999994)
			(stroke
				(width 0)
				(type default)
			)
			(fill no)
			(layer "F.CrtYd")
		)
		(fp_poly
			(pts
				(xy -2.8194 3.6322) (xy -2.8194 -3.6322) (xy 2.8194 -3.6322) (xy 2.8194 1.18364) (xy 2.450084 1.18364)
				(xy 2.450084 -2.999994) (xy -2.450084 -2.999994) (xy -2.450084 2.999994) (xy 2.450084 2.999994)
				(xy 2.450084 1.18618) (xy 2.8194 1.18618) (xy 2.8194 3.6322)
			)
			(stroke
				(width 0)
				(type default)
			)
			(fill no)
			(layer "F.CrtYd")
		)
		(fp_rect
			(start -2.8194 3.6322)
			(end 2.8194 -3.6322)
			(stroke
				(width 0)
				(type default)
			)
			(fill no)
			(layer "F.Fab")
		)
		(pad "1" smd rect
			(at -1.905 2.54 270)
			(size 0.635 1.651)
			(layers "F.Cu" "F.Mask" "F.Paste")
			(net "P5V_HDD21")
		)
		(pad "2" smd rect
			(at -0.635 2.54 270)
			(size 0.635 1.651)
			(layers "F.Cu" "F.Mask" "F.Paste")
			(net "P5V_HDD21")
		)
		(pad "3" smd rect
			(at 0.635 2.54 270)
			(size 0.635 1.651)
			(layers "F.Cu" "F.Mask" "F.Paste")
			(net "P5V_HDD21")
		)
		(pad "4" smd rect
			(at 1.905 2.54 270)
			(size 0.635 1.651)
			(layers "F.Cu" "F.Mask" "F.Paste")
			(net "SW_HDD_P21")
		)
		(pad "5" smd rect
			(at 1.905 -2.54 270)
			(size 0.635 1.651)
			(layers "F.Cu" "F.Mask" "F.Paste")
			(net "P5V_B_4")
		)
		(pad "6" smd rect
			(at 0.635 -2.54 270)
			(size 0.635 1.651)
			(layers "F.Cu" "F.Mask" "F.Paste")
			(net "P5V_B_4")
		)
		(pad "7" smd rect
			(at -0.635 -2.54 270)
			(size 0.635 1.651)
			(layers "F.Cu" "F.Mask" "F.Paste")
			(net "P5V_B_4")
		)
		(pad "8" smd rect
			(at -1.905 -2.54 270)
			(size 0.635 1.651)
			(layers "F.Cu" "F.Mask" "F.Paste")
			(net "P5V_B_4")
		)
	)
	(footprint ""
		(layer "F.Cu")
		(at 423.577004 -368.935 -90)
		(property "Reference" "R957"
			(at 0 0 270)
			(layer "F.SilkS")
			(hide yes)
			(effects
				(font
					(size 1.27 1.27)
				)
			)
		)
		(property "Value" "10KR2F-2-GP"
			(at 0.064008 -3.993896 270)
			(unlocked yes)
			(layer "F.Fab")
			(hide yes)
			(effects
				(font
					(size 1.016 1.016)
					(thickness 0.1524)
				)
			)
		)
		(property "Device Type" "R402H16"
			(at 0.064008 -5.517896 270)
			(unlocked yes)
			(layer "F.Fab")
			(hide yes)
			(effects
				(font
					(size 1.016 1.016)
					(thickness 0.1524)
				)
			)
		)
		(duplicate_pad_numbers_are_jumpers no)
		(fp_line
			(start -0.508 -0.9398)
			(end -0.508 0.9398)
			(stroke
				(width 0.1524)
				(type default)
			)
			(layer "F.SilkS")
		)
		(fp_line
			(start 0.508 -0.9398)
			(end -0.508 -0.9398)
			(stroke
				(width 0.1524)
				(type default)
			)
			(layer "F.SilkS")
		)
		(fp_rect
			(start -0.508 0.9398)
			(end 0.508 -0.9398)
			(stroke
				(width 0)
				(type default)
			)
			(fill no)
			(layer "F.CrtYd")
		)
		(fp_rect
			(start -0.508 0.9398)
			(end 0.508 -0.9398)
			(stroke
				(width 0)
				(type default)
			)
			(fill no)
			(layer "F.Fab")
		)
		(pad "1" smd custom
			(at 0 -0.4445 270)
			(size 0.1397 0.1397)
			(layers "F.Cu" "F.Mask" "F.Paste")
			(net "GND")
			(options
				(clearance outline)
				(anchor circle)
			)
			(primitives
				(gr_poly
					(pts
						(arc
							(start -0.1778 -0.2794)
							(mid -0.249642 -0.249642)
							(end -0.2794 -0.1778)
						)
						(arc
							(start -0.2794 0.1778)
							(mid -0.249642 0.249642)
							(end -0.1778 0.2794)
						)
						(arc
							(start 0.1778 0.2794)
							(mid 0.249642 0.249642)
							(end 0.2794 0.1778)
						)
						(arc
							(start 0.2794 -0.1778)
							(mid 0.249642 -0.249642)
							(end 0.1778 -0.2794)
						)
					)
					(width 0)
					(fill yes)
				)
			)
		)
		(pad "2" smd custom
			(at 0 0.4445 270)
			(size 0.1397 0.1397)
			(layers "F.Cu" "F.Mask" "F.Paste")
			(net "FANTACH_R3")
			(options
				(clearance outline)
				(anchor circle)
			)
			(primitives
				(gr_poly
					(pts
						(arc
							(start -0.1778 -0.2794)
							(mid -0.249642 -0.249642)
							(end -0.2794 -0.1778)
						)
						(arc
							(start -0.2794 0.1778)
							(mid -0.249642 0.249642)
							(end -0.1778 0.2794)
						)
						(arc
							(start 0.1778 0.2794)
							(mid 0.249642 0.249642)
							(end 0.2794 0.1778)
						)
						(arc
							(start 0.2794 -0.1778)
							(mid 0.249642 -0.249642)
							(end 0.1778 -0.2794)
						)
					)
					(width 0)
					(fill yes)
				)
			)
		)
	)
	(footprint ""
		(layer "F.Cu")
		(at 426.879004 -369.697)
		(property "Reference" "C534"
			(at 0 0 0)
			(layer "F.SilkS")
			(hide yes)
			(effects
				(font
					(size 1.27 1.27)
				)
			)
		)
		(property "Value" "SCD1U25V2KX-2-GP"
			(at 1.1811 -2.7051 0)
			(unlocked yes)
			(layer "F.Fab")
			(hide yes)
			(effects
				(font
					(size 1.016 1.016)
					(thickness 0.1524)
				)
			)
		)
		(property "Device Type" "C402H22"
			(at 1.1811 -4.2291 0)
			(unlocked yes)
			(layer "F.Fab")
			(hide yes)
			(effects
				(font
					(size 1.016 1.016)
					(thickness 0.1524)
				)
			)
		)
		(duplicate_pad_numbers_are_jumpers no)
		(fp_rect
			(start -0.4318 0.9525)
			(end 0.4318 -0.9525)
			(stroke
				(width 0)
				(type default)
			)
			(fill no)
			(layer "F.CrtYd")
		)
		(fp_rect
			(start -0.4318 0.9525)
			(end 0.4318 -0.9525)
			(stroke
				(width 0)
				(type default)
			)
			(fill no)
			(layer "F.Fab")
		)
		(pad "1" smd custom
			(at 0 -0.4445)
			(size 0.1524 0.1524)
			(layers "F.Cu" "F.Mask" "F.Paste")
			(net "FAN_3_TACH0")
			(options
				(clearance outline)
				(anchor circle)
			)
			(primitives
				(gr_poly
					(pts
						(arc
							(start 0.3048 -0.2032)
							(mid 0.275042 -0.275042)
							(end 0.2032 -0.3048)
						)
						(arc
							(start -0.2032 -0.3048)
							(mid -0.275042 -0.275042)
							(end -0.3048 -0.2032)
						)
						(arc
							(start -0.3048 0.2032)
							(mid -0.275042 0.275042)
							(end -0.2032 0.3048)
						)
						(arc
							(start 0.2032 0.3048)
							(mid 0.275042 0.275042)
							(end 0.3048 0.2032)
						)
					)
					(width 0)
					(fill yes)
				)
			)
		)
		(pad "2" smd custom
			(at 0 0.4445)
			(size 0.1524 0.1524)
			(layers "F.Cu" "F.Mask" "F.Paste")
			(net "GND")
			(options
				(clearance outline)
				(anchor circle)
			)
			(primitives
				(gr_poly
					(pts
						(arc
							(start 0.3048 -0.2032)
							(mid 0.275042 -0.275042)
							(end 0.2032 -0.3048)
						)
						(arc
							(start -0.2032 -0.3048)
							(mid -0.275042 -0.275042)
							(end -0.3048 -0.2032)
						)
						(arc
							(start -0.3048 0.2032)
							(mid -0.275042 0.275042)
							(end -0.2032 0.3048)
						)
						(arc
							(start 0.2032 0.3048)
							(mid 0.275042 0.275042)
							(end 0.3048 0.2032)
						)
					)
					(width 0)
					(fill yes)
				)
			)
		)
	)
	(footprint ""
		(layer "F.Cu")
		(at 15.24 -248.158 180)
		(property "Reference" "R914"
			(at 0 0 180)
			(layer "F.SilkS")
			(hide yes)
			(effects
				(font
					(size 1.27 1.27)
				)
			)
		)
		(property "Value" "200KR2F-L-GP"
			(at 0.064008 -3.993896 180)
			(unlocked yes)
			(layer "F.Fab")
			(hide yes)
			(effects
				(font
					(size 1.016 1.016)
					(thickness 0.1524)
				)
			)
		)
		(property "Device Type" "R402H16"
			(at 0.064008 -5.517896 180)
			(unlocked yes)
			(layer "F.Fab")
			(hide yes)
			(effects
				(font
					(size 1.016 1.016)
					(thickness 0.1524)
				)
			)
		)
		(duplicate_pad_numbers_are_jumpers no)
		(fp_line
			(start 0.508 -0.9398)
			(end -0.508 -0.9398)
			(stroke
				(width 0.1524)
				(type default)
			)
			(layer "F.SilkS")
		)
		(fp_line
			(start -0.508 -0.9398)
			(end -0.508 0.9398)
			(stroke
				(width 0.1524)
				(type default)
			)
			(layer "F.SilkS")
		)
		(fp_rect
			(start -0.508 0.9398)
			(end 0.508 -0.9398)
			(stroke
				(width 0)
				(type default)
			)
			(fill no)
			(layer "F.CrtYd")
		)
		(fp_rect
			(start -0.508 0.9398)
			(end 0.508 -0.9398)
			(stroke
				(width 0)
				(type default)
			)
			(fill no)
			(layer "F.Fab")
		)
		(pad "1" smd custom
			(at 0 -0.4445 180)
			(size 0.1397 0.1397)
			(layers "F.Cu" "F.Mask" "F.Paste")
			(net "SW_HDD_R0")
			(options
				(clearance outline)
				(anchor circle)
			)
			(primitives
				(gr_poly
					(pts
						(arc
							(start -0.1778 -0.2794)
							(mid -0.249642 -0.249642)
							(end -0.2794 -0.1778)
						)
						(arc
							(start -0.2794 0.1778)
							(mid -0.249642 0.249642)
							(end -0.1778 0.2794)
						)
						(arc
							(start 0.1778 0.2794)
							(mid 0.249642 0.249642)
							(end 0.2794 0.1778)
						)
						(arc
							(start 0.2794 -0.1778)
							(mid 0.249642 -0.249642)
							(end 0.1778 -0.2794)
						)
					)
					(width 0)
					(fill yes)
				)
			)
		)
		(pad "2" smd custom
			(at 0 0.4445 180)
			(size 0.1397 0.1397)
			(layers "F.Cu" "F.Mask" "F.Paste")
			(net "SW_HDD_N0")
			(options
				(clearance outline)
				(anchor circle)
			)
			(primitives
				(gr_poly
					(pts
						(arc
							(start -0.1778 -0.2794)
							(mid -0.249642 -0.249642)
							(end -0.2794 -0.1778)
						)
						(arc
							(start -0.2794 0.1778)
							(mid -0.249642 0.249642)
							(end -0.1778 0.2794)
						)
						(arc
							(start 0.1778 0.2794)
							(mid 0.249642 0.249642)
							(end 0.2794 0.1778)
						)
						(arc
							(start 0.2794 -0.1778)
							(mid 0.249642 -0.249642)
							(end 0.1778 -0.2794)
						)
					)
					(width 0)
					(fill yes)
				)
			)
		)
	)
)
